(kicad_pcb
	(version 20241229)
	(generator "pcbnew")
	(generator_version "9.0")
	(general
		(thickness 1.294)
		(legacy_teardrops no)
	)
	(paper "A3")
	(title_block
		(title "Kintex 410T devboard")
		(date "2024-04-03")
		(rev "1.1.2")
		(comment 9 "footprints 801-806 of 975")
	)
	(layers
		(0 "F.Cu" mixed)
		(4 "In1.Cu" power)
		(6 "In2.Cu" power)
		(8 "In3.Cu" mixed)
		(10 "In4.Cu" power)
		(12 "In5.Cu" mixed)
		(14 "In6.Cu" power)
		(16 "In7.Cu" mixed)
		(18 "In8.Cu" power)
		(2 "B.Cu" mixed)
		(9 "F.Adhes" user "F.Adhesive")
		(11 "B.Adhes" user "B.Adhesive")
		(13 "F.Paste" user)
		(15 "B.Paste" user)
		(5 "F.SilkS" user "F.Silkscreen")
		(7 "B.SilkS" user "B.Silkscreen")
		(1 "F.Mask" user)
		(3 "B.Mask" user)
		(17 "Dwgs.User" user "User.Drawings")
		(19 "Cmts.User" user "User.Comments")
		(21 "Eco1.User" user "User.Eco1")
		(23 "Eco2.User" user "User.Eco2")
		(25 "Edge.Cuts" user)
		(27 "Margin" user)
		(31 "F.CrtYd" user "F.Courtyard")
		(29 "B.CrtYd" user "B.Courtyard")
		(35 "F.Fab" user)
		(33 "B.Fab" user)
	)
	(footprint "antmicro-footprints:C_0402_1005Metric"
		(layer "B.Cu")
		(at 197 140.5)
		(descr "Capacitor SMD 0402")
		(tags "capacitor SMD 0402")
		(property "Reference" "C100"
			(at 1.4 1.2 180)
			(layer "B.SilkS")
			(effects
				(font
					(size 0.7 0.7)
					(thickness 0.15)
				)
				(justify left bottom mirror)
			)
		)
		(property "Value" "C_100n_0402"
			(at 0 -1.169 180)
			(layer "B.Fab")
			(effects
				(font
					(size 0.7 0.7)
					(thickness 0.15)
				)
				(justify left bottom mirror)
			)
		)
		(property "Description" "SMD Multilayer Ceramic Capacitor, 0.1 µF, 50 V, 0402 [1005 Metric], ± 10%, X5R, GRM Series"
			(at 0 0 0)
			(layer "F.Fab")
			(hide yes)
			(effects
				(font
					(size 1.27 1.27)
					(thickness 0.15)
				)
			)
		)
		(property "Author" "Antmicro"
			(at 0 0 0)
			(layer "B.Fab")
			(hide yes)
			(effects
				(font
					(size 1 1)
					(thickness 0.15)
				)
				(justify mirror)
			)
		)
		(property "Dielectric" "X5R"
			(at 0 0 0)
			(layer "B.Fab")
			(hide yes)
			(effects
				(font
					(size 1 1)
					(thickness 0.15)
				)
				(justify mirror)
			)
		)
		(property "License" "Apache-2.0"
			(at 0 0 0)
			(layer "B.Fab")
			(hide yes)
			(effects
				(font
					(size 1 1)
					(thickness 0.15)
				)
				(justify mirror)
			)
		)
		(property "MPN" "GRM155R61H104KE14D"
			(at 0 0 0)
			(layer "B.Fab")
			(hide yes)
			(effects
				(font
					(size 1 1)
					(thickness 0.15)
				)
				(justify mirror)
			)
		)
		(property "Manufacturer" "Murata"
			(at 0 0 0)
			(layer "B.Fab")
			(hide yes)
			(effects
				(font
					(size 1 1)
					(thickness 0.15)
				)
				(justify mirror)
			)
		)
		(property "Val" "100n"
			(at 0 0 0)
			(layer "B.Fab")
			(hide yes)
			(effects
				(font
					(size 1 1)
					(thickness 0.15)
				)
				(justify mirror)
			)
		)
		(property "Voltage" "50V"
			(at 0 0 0)
			(layer "B.Fab")
			(hide yes)
			(effects
				(font
					(size 1 1)
					(thickness 0.15)
				)
				(justify mirror)
			)
		)
		(sheetname "FPGA Bank 18 & 32")
		(sheetfile "fpga-bank-18-32.kicad_sch")
		(attr smd)
		(fp_rect
			(start -0.925 0.47)
			(end 0.925 -0.47)
			(stroke
				(width 0.05)
				(type default)
			)
			(fill no)
			(layer "B.CrtYd")
		)
		(fp_line
			(start -0.494 -0.248)
			(end -0.494 0.25)
			(stroke
				(width 0.15)
				(type solid)
			)
			(layer "B.Fab")
		)
		(fp_line
			(start -0.494 0.25)
			(end 0.504 0.25)
			(stroke
				(width 0.15)
				(type solid)
			)
			(layer "B.Fab")
		)
		(fp_line
			(start 0.504 -0.248)
			(end -0.494 -0.248)
			(stroke
				(width 0.15)
				(type solid)
			)
			(layer "B.Fab")
		)
		(fp_line
			(start 0.504 0.25)
			(end 0.504 -0.248)
			(stroke
				(width 0.15)
				(type solid)
			)
			(layer "B.Fab")
		)
		(pad "1" smd roundrect
			(at -0.48 0)
			(size 0.59 0.64)
			(layers "B.Cu" "B.Mask" "B.Paste")
			(roundrect_rratio 0.25)
			(net 1 "GND")
			(pintype "passive")
		)
		(pad "2" smd roundrect
			(at 0.48 0)
			(size 0.59 0.64)
			(layers "B.Cu" "B.Mask" "B.Paste")
			(roundrect_rratio 0.25)
			(net 26 "+1V8")
			(pintype "passive")
		)
	)
	(footprint "antmicro-footprints:QFN-2L_1.6x1x0.55mm"
		(layer "B.Cu")
		(at 264.75 79.4 90)
		(property "Reference" "D35"
			(at -1.9 -0.75 90)
			(layer "B.SilkS")
			(effects
				(font
					(size 0.7 0.7)
					(thickness 0.15)
				)
				(justify right bottom mirror)
			)
		)
		(property "Value" "ESDA25P35-1U1M"
			(at 0 -1.7 90)
			(layer "B.Fab")
			(effects
				(font
					(size 0.7 0.7)
					(thickness 0.15)
				)
				(justify right bottom mirror)
			)
		)
		(property "Description" "Unidirectional TVS, 30 kV, QFN-2L, 22 V, 195 pF"
			(at 0 0 90)
			(layer "F.Fab")
			(hide yes)
			(effects
				(font
					(size 1.27 1.27)
					(thickness 0.15)
				)
			)
		)
		(property "Author" "Antmicro"
			(at 344.15 -185.35 0)
			(layer "B.Fab")
			(hide yes)
			(effects
				(font
					(size 1 1)
					(thickness 0.15)
				)
				(justify mirror)
			)
		)
		(property "License" "Apache-2.0"
			(at 344.15 -185.35 0)
			(layer "B.Fab")
			(hide yes)
			(effects
				(font
					(size 1 1)
					(thickness 0.15)
				)
				(justify mirror)
			)
		)
		(property "MPN" "ESDA25P35-1U1M"
			(at 344.15 -185.35 0)
			(layer "B.Fab")
			(hide yes)
			(effects
				(font
					(size 1 1)
					(thickness 0.15)
				)
				(justify mirror)
			)
		)
		(property "Manufacturer" "STMicroelectronics"
			(at 344.15 -185.35 0)
			(layer "B.Fab")
			(hide yes)
			(effects
				(font
					(size 1 1)
					(thickness 0.15)
				)
				(justify mirror)
			)
		)
		(property "Public" "False"
			(at 344.15 -185.35 0)
			(layer "B.Fab")
			(hide yes)
			(effects
				(font
					(size 1 1)
					(thickness 0.15)
				)
				(justify mirror)
			)
		)
		(sheetname "User GPIO + LED + button + DIP switch")
		(sheetfile "user-gpio.kicad_sch")
		(attr smd)
		(fp_line
			(start 0.27 -0.3)
			(end -0.27 -0.3)
			(stroke
				(width 0.15)
				(type solid)
			)
			(layer "B.SilkS")
		)
		(fp_line
			(start 0.27 0.3)
			(end -0.27 0.3)
			(stroke
				(width 0.15)
				(type solid)
			)
			(layer "B.SilkS")
		)
		(fp_line
			(start -1.2 0.4)
			(end -1.2 -0.4)
			(stroke
				(width 0.15)
				(type solid)
			)
			(layer "B.SilkS")
		)
		(fp_rect
			(start 1.25 -0.65)
			(end -1.25 0.65)
			(stroke
				(width 0.05)
				(type solid)
			)
			(fill no)
			(layer "B.CrtYd")
		)
		(fp_line
			(start 0.201 -0.2)
			(end 0.201 0)
			(stroke
				(width 0.15)
				(type solid)
			)
			(layer "B.Fab")
		)
		(fp_line
			(start -0.199 -0.2)
			(end -0.199 -0.1)
			(stroke
				(width 0.15)
				(type solid)
			)
			(layer "B.Fab")
		)
		(fp_line
			(start 0.599 0)
			(end 0.201 0)
			(stroke
				(width 0.15)
				(type solid)
			)
			(layer "B.Fab")
		)
		(fp_line
			(start 0.201 0)
			(end 0.201 0.202)
			(stroke
				(width 0.15)
				(type solid)
			)
			(layer "B.Fab")
		)
		(fp_line
			(start -0.101 0)
			(end 0.201 -0.2)
			(stroke
				(width 0.15)
				(type solid)
			)
			(layer "B.Fab")
		)
		(fp_line
			(start -0.199 0)
			(end -0.597 0)
			(stroke
				(width 0.15)
				(type solid)
			)
			(layer "B.Fab")
		)
		(fp_line
			(start 0.201 0.202)
			(end -0.101 0)
			(stroke
				(width 0.15)
				(type solid)
			)
			(layer "B.Fab")
		)
		(fp_line
			(start -0.199 0.202)
			(end -0.199 -0.1)
			(stroke
				(width 0.15)
				(type solid)
			)
			(layer "B.Fab")
		)
		(fp_rect
			(start 0.848 -0.4)
			(end -0.85 0.402)
			(stroke
				(width 0.15)
				(type solid)
			)
			(fill no)
			(layer "B.Fab")
		)
		(pad "1" smd roundrect
			(at -0.7 0 270)
			(size 0.8 1)
			(layers "B.Cu" "B.Mask" "B.Paste")
			(roundrect_rratio 0.2)
			(net 1228 "/USER_IO.BUTTON0")
			(pinfunction "C")
			(pintype "passive")
		)
		(pad "2" smd roundrect
			(at 0.7 0 270)
			(size 0.8 1)
			(layers "B.Cu" "B.Mask" "B.Paste")
			(roundrect_rratio 0.2)
			(net 1 "GND")
			(pinfunction "A")
			(pintype "passive")
		)
	)
	(footprint "antmicro-footprints:C_0402_1005Metric"
		(layer "B.Cu")
		(at 210.5 117 90)
		(descr "Capacitor SMD 0402")
		(tags "capacitor SMD 0402")
		(property "Reference" "C27"
			(at 1.125 1.25 270)
			(layer "B.SilkS")
			(effects
				(font
					(size 0.7 0.7)
					(thickness 0.15)
				)
				(justify left bottom mirror)
			)
		)
		(property "Value" "C_100n_0402"
			(at 0 -1.169 270)
			(layer "B.Fab")
			(effects
				(font
					(size 0.7 0.7)
					(thickness 0.15)
				)
				(justify left bottom mirror)
			)
		)
		(property "Description" "SMD Multilayer Ceramic Capacitor, 0.1 µF, 50 V, 0402 [1005 Metric], ± 10%, X5R, GRM Series"
			(at 0 0 90)
			(layer "F.Fab")
			(hide yes)
			(effects
				(font
					(size 1.27 1.27)
					(thickness 0.15)
				)
			)
		)
		(property "Author" "Antmicro"
			(at 327.5 -93.5 0)
			(layer "B.Fab")
			(hide yes)
			(effects
				(font
					(size 1 1)
					(thickness 0.15)
				)
				(justify mirror)
			)
		)
		(property "Dielectric" "X5R"
			(at 327.5 -93.5 0)
			(layer "B.Fab")
			(hide yes)
			(effects
				(font
					(size 1 1)
					(thickness 0.15)
				)
				(justify mirror)
			)
		)
		(property "License" "Apache-2.0"
			(at 327.5 -93.5 0)
			(layer "B.Fab")
			(hide yes)
			(effects
				(font
					(size 1 1)
					(thickness 0.15)
				)
				(justify mirror)
			)
		)
		(property "MPN" "GRM155R61H104KE14D"
			(at 327.5 -93.5 0)
			(layer "B.Fab")
			(hide yes)
			(effects
				(font
					(size 1 1)
					(thickness 0.15)
				)
				(justify mirror)
			)
		)
		(property "Manufacturer" "Murata"
			(at 327.5 -93.5 0)
			(layer "B.Fab")
			(hide yes)
			(effects
				(font
					(size 1 1)
					(thickness 0.15)
				)
				(justify mirror)
			)
		)
		(property "Val" "100n"
			(at 327.5 -93.5 0)
			(layer "B.Fab")
			(hide yes)
			(effects
				(font
					(size 1 1)
					(thickness 0.15)
				)
				(justify mirror)
			)
		)
		(property "Voltage" "50V"
			(at 327.5 -93.5 0)
			(layer "B.Fab")
			(hide yes)
			(effects
				(font
					(size 1 1)
					(thickness 0.15)
				)
				(justify mirror)
			)
		)
		(sheetname "FPGA Bank 16 & 17")
		(sheetfile "fpga-bank-16-17.kicad_sch")
		(attr smd)
		(fp_rect
			(start -0.925 0.47)
			(end 0.925 -0.47)
			(stroke
				(width 0.05)
				(type default)
			)
			(fill no)
			(layer "B.CrtYd")
		)
		(fp_line
			(start 0.504 -0.248)
			(end -0.494 -0.248)
			(stroke
				(width 0.15)
				(type solid)
			)
			(layer "B.Fab")
		)
		(fp_line
			(start -0.494 -0.248)
			(end -0.494 0.25)
			(stroke
				(width 0.15)
				(type solid)
			)
			(layer "B.Fab")
		)
		(fp_line
			(start 0.504 0.25)
			(end 0.504 -0.248)
			(stroke
				(width 0.15)
				(type solid)
			)
			(layer "B.Fab")
		)
		(fp_line
			(start -0.494 0.25)
			(end 0.504 0.25)
			(stroke
				(width 0.15)
				(type solid)
			)
			(layer "B.Fab")
		)
		(pad "1" smd roundrect
			(at -0.48 0 90)
			(size 0.59 0.64)
			(layers "B.Cu" "B.Mask" "B.Paste")
			(roundrect_rratio 0.25)
			(net 1 "GND")
			(pintype "passive")
		)
		(pad "2" smd roundrect
			(at 0.48 0 90)
			(size 0.59 0.64)
			(layers "B.Cu" "B.Mask" "B.Paste")
			(roundrect_rratio 0.25)
			(net 3 "VCC_USR_B")
			(pintype "passive")
		)
	)
	(footprint "antmicro-footprints:C_0402_1005Metric"
		(layer "B.Cu")
		(at 196.85 131.25)
		(descr "Capacitor SMD 0402")
		(tags "capacitor SMD 0402")
		(property "Reference" "C63"
			(at 25 -28.025 180)
			(layer "B.SilkS")
			(effects
				(font
					(size 0.7 0.7)
					(thickness 0.15)
				)
				(justify left bottom mirror)
			)
		)
		(property "Value" "C_100n_0402"
			(at 0 -1.169 180)
			(layer "B.Fab")
			(effects
				(font
					(size 0.7 0.7)
					(thickness 0.15)
				)
				(justify left bottom mirror)
			)
		)
		(property "Description" "SMD Multilayer Ceramic Capacitor, 0.1 µF, 50 V, 0402 [1005 Metric], ± 10%, X5R, GRM Series"
			(at 0 0 0)
			(layer "F.Fab")
			(hide yes)
			(effects
				(font
					(size 1.27 1.27)
					(thickness 0.15)
				)
			)
		)
		(property "Author" "Antmicro"
			(at 0 0 0)
			(layer "B.Fab")
			(hide yes)
			(effects
				(font
					(size 1 1)
					(thickness 0.15)
				)
				(justify mirror)
			)
		)
		(property "Dielectric" "X5R"
			(at 0 0 0)
			(layer "B.Fab")
			(hide yes)
			(effects
				(font
					(size 1 1)
					(thickness 0.15)
				)
				(justify mirror)
			)
		)
		(property "License" "Apache-2.0"
			(at 0 0 0)
			(layer "B.Fab")
			(hide yes)
			(effects
				(font
					(size 1 1)
					(thickness 0.15)
				)
				(justify mirror)
			)
		)
		(property "MPN" "GRM155R61H104KE14D"
			(at 0 0 0)
			(layer "B.Fab")
			(hide yes)
			(effects
				(font
					(size 1 1)
					(thickness 0.15)
				)
				(justify mirror)
			)
		)
		(property "Manufacturer" "Murata"
			(at 0 0 0)
			(layer "B.Fab")
			(hide yes)
			(effects
				(font
					(size 1 1)
					(thickness 0.15)
				)
				(justify mirror)
			)
		)
		(property "Val" "100n"
			(at 0 0 0)
			(layer "B.Fab")
			(hide yes)
			(effects
				(font
					(size 1 1)
					(thickness 0.15)
				)
				(justify mirror)
			)
		)
		(property "Voltage" "50V"
			(at 0 0 0)
			(layer "B.Fab")
			(hide yes)
			(effects
				(font
					(size 1 1)
					(thickness 0.15)
				)
				(justify mirror)
			)
		)
		(sheetname "FPGA supply")
		(sheetfile "fpga-supply.kicad_sch")
		(attr smd)
		(fp_rect
			(start -0.925 0.47)
			(end 0.925 -0.47)
			(stroke
				(width 0.05)
				(type default)
			)
			(fill no)
			(layer "B.CrtYd")
		)
		(fp_line
			(start -0.494 -0.248)
			(end -0.494 0.25)
			(stroke
				(width 0.15)
				(type solid)
			)
			(layer "B.Fab")
		)
		(fp_line
			(start -0.494 0.25)
			(end 0.504 0.25)
			(stroke
				(width 0.15)
				(type solid)
			)
			(layer "B.Fab")
		)
		(fp_line
			(start 0.504 -0.248)
			(end -0.494 -0.248)
			(stroke
				(width 0.15)
				(type solid)
			)
			(layer "B.Fab")
		)
		(fp_line
			(start 0.504 0.25)
			(end 0.504 -0.248)
			(stroke
				(width 0.15)
				(type solid)
			)
			(layer "B.Fab")
		)
		(pad "1" smd roundrect
			(at -0.48 0)
			(size 0.59 0.64)
			(layers "B.Cu" "B.Mask" "B.Paste")
			(roundrect_rratio 0.25)
			(net 1 "GND")
			(pintype "passive")
		)
		(pad "2" smd roundrect
			(at 0.48 0)
			(size 0.59 0.64)
			(layers "B.Cu" "B.Mask" "B.Paste")
			(roundrect_rratio 0.25)
			(net 26 "+1V8")
			(pintype "passive")
		)
	)
	(footprint "antmicro-footprints:R_0402_1005Metric"
		(layer "B.Cu")
		(at 265.401 173)
		(descr "Resistor SMD 0402")
		(tags "resistor SMD 0402")
		(property "Reference" "R246"
			(at 3.649 0.35 180)
			(layer "B.SilkS")
			(effects
				(font
					(size 0.7 0.7)
					(thickness 0.15)
				)
				(justify left bottom mirror)
			)
		)
		(property "Value" "R_10R_0402"
			(at 0 -1.4 180)
			(layer "B.Fab")
			(effects
				(font
					(size 0.7 0.7)
					(thickness 0.15)
				)
				(justify left bottom mirror)
			)
		)
		(property "Description" "SMD Chip Resistor, 10 ohm, ± 1%, 62.5 mW, 0402 [1005 Metric], Thick Film, General Purpose"
			(at 0 0 0)
			(layer "F.Fab")
			(hide yes)
			(effects
				(font
					(size 1.27 1.27)
					(thickness 0.15)
				)
			)
		)
		(property "Author" "Antmicro"
			(at 0 0 0)
			(layer "B.Fab")
			(hide yes)
			(effects
				(font
					(size 1 1)
					(thickness 0.15)
				)
				(justify mirror)
			)
		)
		(property "License" "Apache-2.0"
			(at 0 0 0)
			(layer "B.Fab")
			(hide yes)
			(effects
				(font
					(size 1 1)
					(thickness 0.15)
				)
				(justify mirror)
			)
		)
		(property "MPN" "CR0402-FX-10R0GLF"
			(at 0 0 0)
			(layer "B.Fab")
			(hide yes)
			(effects
				(font
					(size 1 1)
					(thickness 0.15)
				)
				(justify mirror)
			)
		)
		(property "Manufacturer" "Bourns"
			(at 0 0 0)
			(layer "B.Fab")
			(hide yes)
			(effects
				(font
					(size 1 1)
					(thickness 0.15)
				)
				(justify mirror)
			)
		)
		(property "Tolerance" "1%"
			(at 0 0 0)
			(layer "B.Fab")
			(hide yes)
			(effects
				(font
					(size 1 1)
					(thickness 0.15)
				)
				(justify mirror)
			)
		)
		(property "Val" "10R"
			(at 0 0 0)
			(layer "B.Fab")
			(hide yes)
			(effects
				(font
					(size 1 1)
					(thickness 0.15)
				)
				(justify mirror)
			)
		)
		(sheetname "HDMI + Ethernet")
		(sheetfile "hdmi-ethernet.kicad_sch")
		(attr smd)
		(fp_rect
			(start -0.925 0.47)
			(end 0.925 -0.47)
			(stroke
				(width 0.05)
				(type default)
			)
			(fill no)
			(layer "B.CrtYd")
		)
		(fp_rect
			(start -0.5 0.25)
			(end 0.5 -0.25)
			(stroke
				(width 0.15)
				(type solid)
			)
			(fill no)
			(layer "B.Fab")
		)
		(pad "1" smd roundrect
			(at -0.48 0)
			(size 0.59 0.64)
			(layers "B.Cu" "B.Mask" "B.Paste")
			(roundrect_rratio 0.25)
			(net 1 "GND")
			(pintype "passive")
		)
		(pad "2" smd roundrect
			(at 0.48 0)
			(size 0.59 0.64)
			(layers "B.Cu" "B.Mask" "B.Paste")
			(roundrect_rratio 0.25)
			(net 723 "/HDMI + Ethernet/ETH_CONN_SH")
			(pintype "passive")
		)
	)
	(footprint "antmicro-footprints:R_0402_1005Metric"
		(layer "B.Cu")
		(at 250.301 141.25 -90)
		(descr "Resistor SMD 0402")
		(tags "resistor SMD 0402")
		(property "Reference" "R87"
			(at 0.75 -0.399 90)
			(layer "B.SilkS")
			(effects
				(font
					(size 0.7 0.7)
					(thickness 0.15)
				)
				(justify left bottom mirror)
			)
		)
		(property "Value" "R_10k_0402"
			(at 0 -1.4 90)
			(layer "B.Fab")
			(effects
				(font
					(size 0.7 0.7)
					(thickness 0.15)
				)
				(justify left bottom mirror)
			)
		)
		(property "Description" "SMD Chip Resistor, 10 kohm, ± 1%, 62.5 mW, 0402 [1005 Metric], Thick Film, General Purpose"
			(at 0 0 270)
			(layer "F.Fab")
			(hide yes)
			(effects
				(font
					(size 1.27 1.27)
					(thickness 0.15)
				)
			)
		)
		(property "Author" "Antmicro"
			(at 109.051 391.551 0)
			(layer "B.Fab")
			(hide yes)
			(effects
				(font
					(size 1 1)
					(thickness 0.15)
				)
				(justify mirror)
			)
		)
		(property "License" "Apache-2.0"
			(at 109.051 391.551 0)
			(layer "B.Fab")
			(hide yes)
			(effects
				(font
					(size 1 1)
					(thickness 0.15)
				)
				(justify mirror)
			)
		)
		(property "MPN" "CR0402-FX-1002GLF"
			(at 109.051 391.551 0)
			(layer "B.Fab")
			(hide yes)
			(effects
				(font
					(size 1 1)
					(thickness 0.15)
				)
				(justify mirror)
			)
		)
		(property "Manufacturer" "Bourns"
			(at 109.051 391.551 0)
			(layer "B.Fab")
			(hide yes)
			(effects
				(font
					(size 1 1)
					(thickness 0.15)
				)
				(justify mirror)
			)
		)
		(property "Tolerance" "1%"
			(at 109.051 391.551 0)
			(layer "B.Fab")
			(hide yes)
			(effects
				(font
					(size 1 1)
					(thickness 0.15)
				)
				(justify mirror)
			)
		)
		(property "Val" "10k"
			(at 109.051 391.551 0)
			(layer "B.Fab")
			(hide yes)
			(effects
				(font
					(size 1 1)
					(thickness 0.15)
				)
				(justify mirror)
			)
		)
		(sheetname "SPI Flash + SD Card")
		(sheetfile "spi-flash.kicad_sch")
		(attr smd)
		(fp_rect
			(start -0.925 0.47)
			(end 0.925 -0.47)
			(stroke
				(width 0.05)
				(type default)
			)
			(fill no)
			(layer "B.CrtYd")
		)
		(fp_rect
			(start -0.5 0.25)
			(end 0.5 -0.25)
			(stroke
				(width 0.15)
				(type solid)
			)
			(fill no)
			(layer "B.Fab")
		)
		(pad "1" smd roundrect
			(at -0.48 0 270)
			(size 0.59 0.64)
			(layers "B.Cu" "B.Mask" "B.Paste")
			(roundrect_rratio 0.25)
			(net 391 "/FPGA Bank 33 & 34/SD_CARD.DAT3")
			(pintype "passive")
		)
		(pad "2" smd roundrect
			(at 0.48 0 270)
			(size 0.59 0.64)
			(layers "B.Cu" "B.Mask" "B.Paste")
			(roundrect_rratio 0.25)
			(net 24 "+3V3")
			(pintype "passive")
		)
	)
)
